(kicad_pcb
	(version 20260206)
	(generator "pcbnew")
	(generator_version "10.0")
	(general
		(thickness 1.6)
		(legacy_teardrops no)
	)
	(paper "A4")
	(title_block
		(title "04192023_DAF0TMB3IC0_F0TG_MB_C_brd_V02_OCP.brd")
		(comment 1 "Grand Teton / footprints 8156-8161 of 8354")
	)
	(layers
		(0 "F.Cu" signal "TOP")
		(4 "In1.Cu" signal "GND")
		(6 "In2.Cu" signal "IN1")
		(8 "In3.Cu" signal "GND1")
		(10 "In4.Cu" signal "IN2")
		(12 "In5.Cu" signal "GND2")
		(14 "In6.Cu" signal "IN3")
		(16 "In7.Cu" signal "GND3")
		(18 "In8.Cu" signal "VCC")
		(20 "In9.Cu" signal "VCC1")
		(22 "In10.Cu" signal "GND4")
		(24 "In11.Cu" signal "IN4")
		(26 "In12.Cu" signal "GND5")
		(28 "In13.Cu" signal "IN5")
		(30 "In14.Cu" signal "GND6")
		(32 "In15.Cu" signal "IN6")
		(34 "In16.Cu" signal "GND7")
		(2 "B.Cu" signal "BOTTOM")
		(9 "F.Adhes" user "F.Adhesive")
		(11 "B.Adhes" user "B.Adhesive")
		(13 "F.Paste" user "Package Geometry/Pastemask Top")
		(15 "B.Paste" user "Package Geometry/Pastemask Bottom")
		(5 "F.SilkS" user "Ref Des/Silkscreen Top")
		(7 "B.SilkS" user "Ref Des/Silkscreen Bottom")
		(1 "F.Mask" user "Board Geometry/Soldermask Top")
		(3 "B.Mask" user "Board Geometry/Soldermask Bottom")
		(17 "Dwgs.User" user "User.Drawings")
		(19 "Cmts.User" user "User.Comments")
		(21 "Eco1.User" user "User.Eco1")
		(23 "Eco2.User" user "User.Eco2")
		(25 "Edge.Cuts" user "Board Geometry/Outline")
		(27 "Margin" user)
		(31 "F.CrtYd" user "Package Geometry/Place Bound Top")
		(29 "B.CrtYd" user "Package Geometry/Place Bound Bottom")
		(35 "F.Fab" user "Ref Des/Assembly Top")
		(33 "B.Fab" user "Ref Des/Assembly Bottom")
	)
	(footprint ""
		(layer "B.Cu")
		(at 73.068434 -386.745988 -90)
		(property "Reference" "C118"
			(at 0 0 90)
			(layer "B.SilkS")
			(hide yes)
			(effects
				(font
					(size 1.27 1.27)
				)
				(justify mirror)
			)
		)
		(property "Value" ""
			(at 0 0 90)
			(layer "B.Fab")
			(effects
				(font
					(size 1.27 1.27)
				)
				(justify mirror)
			)
		)
		(duplicate_pad_numbers_are_jumpers no)
		(fp_line
			(start -0.7874 0.4064)
			(end 0.7874 0.4064)
			(stroke
				(width 0.1524)
				(type default)
			)
			(layer "B.SilkS")
		)
		(fp_line
			(start 0.7874 0.4064)
			(end 0.7874 -0.4064)
			(stroke
				(width 0.1524)
				(type default)
			)
			(layer "B.SilkS")
		)
		(fp_line
			(start -0.7874 -0.4064)
			(end -0.7874 0.4064)
			(stroke
				(width 0.1524)
				(type default)
			)
			(layer "B.SilkS")
		)
		(fp_line
			(start 0.7874 -0.4064)
			(end -0.7874 -0.4064)
			(stroke
				(width 0.1524)
				(type default)
			)
			(layer "B.SilkS")
		)
		(fp_line
			(start -0.67945 0.3048)
			(end -0.120396 0.3048)
			(stroke
				(width 0.1)
				(type default)
			)
			(layer "B.Fab")
		)
		(fp_line
			(start -0.120396 0.3048)
			(end -0.120396 0.2794)
			(stroke
				(width 0.1)
				(type default)
			)
			(layer "B.Fab")
		)
		(fp_line
			(start 0.12065 0.3048)
			(end 0.67945 0.3048)
			(stroke
				(width 0.1)
				(type default)
			)
			(layer "B.Fab")
		)
		(fp_line
			(start 0.67945 0.3048)
			(end 0.67945 -0.305054)
			(stroke
				(width 0.1)
				(type default)
			)
			(layer "B.Fab")
		)
		(fp_line
			(start -0.120396 0.2794)
			(end 0.12065 0.2794)
			(stroke
				(width 0.1)
				(type default)
			)
			(layer "B.Fab")
		)
		(fp_line
			(start 0.12065 0.2794)
			(end 0.12065 0.3048)
			(stroke
				(width 0.1)
				(type default)
			)
			(layer "B.Fab")
		)
		(fp_line
			(start -0.12065 -0.2794)
			(end -0.12065 -0.3048)
			(stroke
				(width 0.1)
				(type default)
			)
			(layer "B.Fab")
		)
		(fp_line
			(start 0.12065 -0.2794)
			(end -0.12065 -0.2794)
			(stroke
				(width 0.1)
				(type default)
			)
			(layer "B.Fab")
		)
		(fp_line
			(start -0.67945 -0.3048)
			(end -0.67945 0.3048)
			(stroke
				(width 0.1)
				(type default)
			)
			(layer "B.Fab")
		)
		(fp_line
			(start -0.12065 -0.3048)
			(end -0.67945 -0.3048)
			(stroke
				(width 0.1)
				(type default)
			)
			(layer "B.Fab")
		)
		(fp_line
			(start 0.12065 -0.305054)
			(end 0.12065 -0.2794)
			(stroke
				(width 0.1)
				(type default)
			)
			(layer "B.Fab")
		)
		(fp_line
			(start 0.67945 -0.305054)
			(end 0.12065 -0.305054)
			(stroke
				(width 0.1)
				(type default)
			)
			(layer "B.Fab")
		)
		(pad "1" smd circle
			(at 0.40005 0 90)
			(size 0 0)
			(layers "B.Cu" "B.Mask" "B.Paste")
			(net "P1V8_CPU1_RT_1D")
		)
		(pad "2" smd circle
			(at -0.40005 0 90)
			(size 0 0)
			(layers "B.Cu" "B.Mask" "B.Paste")
			(net "GND")
		)
	)
	(footprint ""
		(layer "B.Cu")
		(at 119.34698 -169.258234 90)
		(property "Reference" "PR211"
			(at 0 0 90)
			(layer "B.SilkS")
			(hide yes)
			(effects
				(font
					(size 1.27 1.27)
				)
				(justify mirror)
			)
		)
		(property "Value" ""
			(at 0 0 90)
			(layer "B.Fab")
			(effects
				(font
					(size 1.27 1.27)
				)
				(justify mirror)
			)
		)
		(duplicate_pad_numbers_are_jumpers no)
		(fp_line
			(start 0.7874 -0.4064)
			(end -0.7874 -0.4064)
			(stroke
				(width 0.1524)
				(type default)
			)
			(layer "B.SilkS")
		)
		(fp_line
			(start -0.7874 -0.4064)
			(end -0.7874 0.4064)
			(stroke
				(width 0.1524)
				(type default)
			)
			(layer "B.SilkS")
		)
		(fp_line
			(start 0.7874 0.4064)
			(end 0.7874 -0.4064)
			(stroke
				(width 0.1524)
				(type default)
			)
			(layer "B.SilkS")
		)
		(fp_line
			(start -0.7874 0.4064)
			(end 0.7874 0.4064)
			(stroke
				(width 0.1524)
				(type default)
			)
			(layer "B.SilkS")
		)
		(fp_line
			(start 0.67945 -0.305054)
			(end 0.12065 -0.305054)
			(stroke
				(width 0.1)
				(type default)
			)
			(layer "B.Fab")
		)
		(fp_line
			(start 0.12065 -0.305054)
			(end 0.12065 -0.2794)
			(stroke
				(width 0.1)
				(type default)
			)
			(layer "B.Fab")
		)
		(fp_line
			(start -0.12065 -0.3048)
			(end -0.67945 -0.3048)
			(stroke
				(width 0.1)
				(type default)
			)
			(layer "B.Fab")
		)
		(fp_line
			(start -0.67945 -0.3048)
			(end -0.67945 0.3048)
			(stroke
				(width 0.1)
				(type default)
			)
			(layer "B.Fab")
		)
		(fp_line
			(start 0.12065 -0.2794)
			(end -0.12065 -0.2794)
			(stroke
				(width 0.1)
				(type default)
			)
			(layer "B.Fab")
		)
		(fp_line
			(start -0.12065 -0.2794)
			(end -0.12065 -0.3048)
			(stroke
				(width 0.1)
				(type default)
			)
			(layer "B.Fab")
		)
		(fp_line
			(start 0.12065 0.2794)
			(end 0.12065 0.3048)
			(stroke
				(width 0.1)
				(type default)
			)
			(layer "B.Fab")
		)
		(fp_line
			(start -0.120396 0.2794)
			(end 0.12065 0.2794)
			(stroke
				(width 0.1)
				(type default)
			)
			(layer "B.Fab")
		)
		(fp_line
			(start 0.67945 0.3048)
			(end 0.67945 -0.305054)
			(stroke
				(width 0.1)
				(type default)
			)
			(layer "B.Fab")
		)
		(fp_line
			(start 0.12065 0.3048)
			(end 0.67945 0.3048)
			(stroke
				(width 0.1)
				(type default)
			)
			(layer "B.Fab")
		)
		(fp_line
			(start -0.120396 0.3048)
			(end -0.120396 0.2794)
			(stroke
				(width 0.1)
				(type default)
			)
			(layer "B.Fab")
		)
		(fp_line
			(start -0.67945 0.3048)
			(end -0.120396 0.3048)
			(stroke
				(width 0.1)
				(type default)
			)
			(layer "B.Fab")
		)
		(pad "1" smd circle
			(at 0.40005 0 270)
			(size 0 0)
			(layers "B.Cu" "B.Mask" "B.Paste")
			(net "PVDDCR_SOC_P1_VOS1")
		)
		(pad "2" smd circle
			(at -0.40005 0 270)
			(size 0 0)
			(layers "B.Cu" "B.Mask" "B.Paste")
			(net "PVDDCR_SOC_P1")
		)
	)
	(footprint ""
		(layer "B.Cu")
		(at 341.024718 -389.49503 180)
		(property "Reference" "C7011"
			(at -1.921764 -3.055112 0)
			(unlocked yes)
			(layer "B.SilkS")
			(effects
				(font
					(size 0.7874 0.5842)
					(thickness 0.1524)
				)
				(justify left mirror)
			)
		)
		(property "Value" ""
			(at 0 0 0)
			(layer "B.Fab")
			(effects
				(font
					(size 1.27 1.27)
				)
				(justify mirror)
			)
		)
		(duplicate_pad_numbers_are_jumpers no)
		(fp_line
			(start 4.84378 -2.150618)
			(end 4.842256 2.163064)
			(stroke
				(width 0.1524)
				(type default)
			)
			(layer "B.SilkS")
		)
		(fp_line
			(start 4.84378 -2.150618)
			(end 4.53898 -2.150618)
			(stroke
				(width 0.1524)
				(type default)
			)
			(layer "B.SilkS")
		)
		(fp_line
			(start 4.83108 2.150364)
			(end 4.447794 2.149348)
			(stroke
				(width 0.1524)
				(type default)
			)
			(layer "B.SilkS")
		)
		(fp_line
			(start 4.69138 -2.150618)
			(end 4.692396 2.161032)
			(stroke
				(width 0.1524)
				(type default)
			)
			(layer "B.SilkS")
		)
		(fp_line
			(start 4.53898 2.15011)
			(end 4.53898 -2.15011)
			(stroke
				(width 0.1524)
				(type default)
			)
			(layer "B.SilkS")
		)
		(fp_line
			(start 4.53898 -2.15011)
			(end -4.53898 -2.15011)
			(stroke
				(width 0.1524)
				(type default)
			)
			(layer "B.SilkS")
		)
		(fp_line
			(start 4.53898 -2.150618)
			(end 4.539742 2.152142)
			(stroke
				(width 0.1524)
				(type default)
			)
			(layer "B.SilkS")
		)
		(fp_line
			(start -4.53898 2.15011)
			(end 4.53898 2.15011)
			(stroke
				(width 0.1524)
				(type default)
			)
			(layer "B.SilkS")
		)
		(fp_line
			(start -4.53898 -2.15011)
			(end -4.53898 2.15011)
			(stroke
				(width 0.1524)
				(type default)
			)
			(layer "B.SilkS")
		)
		(fp_line
			(start 3.64998 2.15011)
			(end 3.64998 -2.15011)
			(stroke
				(width 0.1)
				(type default)
			)
			(layer "B.Fab")
		)
		(fp_line
			(start 3.64998 -2.15011)
			(end -3.64998 -2.15011)
			(stroke
				(width 0.1)
				(type default)
			)
			(layer "B.Fab")
		)
		(fp_line
			(start -3.64998 2.15011)
			(end 3.64998 2.15011)
			(stroke
				(width 0.1)
				(type default)
			)
			(layer "B.Fab")
		)
		(fp_line
			(start -3.64998 -2.15011)
			(end -3.64998 2.15011)
			(stroke
				(width 0.1)
				(type default)
			)
			(layer "B.Fab")
		)
		(fp_text user "+"
			(at 4.327652 -3.024378 180)
			(unlocked yes)
			(layer "B.SilkS")
			(effects
				(font
					(size 1.905 1.4224)
					(thickness 0.1524)
				)
				(justify left mirror)
			)
		)
		(fp_text user "-"
			(at -3.132074 -2.758948 180)
			(unlocked yes)
			(layer "B.SilkS")
			(effects
				(font
					(size 1.905 1.4224)
					(thickness 0.1524)
				)
				(justify left mirror)
			)
		)
		(fp_text user "+"
			(at 6.214872 -0.337058 180)
			(unlocked yes)
			(layer "B.Fab")
			(effects
				(font
					(size 1.905 1.4224)
					(thickness 0.1524)
				)
				(justify left mirror)
			)
		)
		(fp_text user "-"
			(at -4.313174 -0.094488 180)
			(unlocked yes)
			(layer "B.Fab")
			(effects
				(font
					(size 1.905 1.4224)
					(thickness 0.1524)
				)
				(justify left mirror)
			)
		)
		(pad "1" smd rect
			(at 3.199892 0)
			(size 2.413 2.8194)
			(layers "B.Cu" "B.Mask" "B.Paste")
			(net "P0V9_CPU0_RT1_2A")
		)
		(pad "2" smd rect
			(at -3.199892 0)
			(size 2.413 2.8194)
			(layers "B.Cu" "B.Mask" "B.Paste")
			(net "GND")
		)
	)
	(footprint ""
		(layer "B.Cu")
		(at 433.235608 -354.89769 -90)
		(property "Reference" "PC216_2"
			(at 0 0 90)
			(layer "B.SilkS")
			(hide yes)
			(effects
				(font
					(size 1.27 1.27)
				)
				(justify mirror)
			)
		)
		(property "Value" ""
			(at 0 0 90)
			(layer "B.Fab")
			(effects
				(font
					(size 1.27 1.27)
				)
				(justify mirror)
			)
		)
		(duplicate_pad_numbers_are_jumpers no)
		(fp_line
			(start -1.524 0.762)
			(end 1.524 0.762)
			(stroke
				(width 0.1524)
				(type default)
			)
			(layer "B.SilkS")
		)
		(fp_line
			(start 1.524 0.762)
			(end 1.524 -0.762)
			(stroke
				(width 0.1524)
				(type default)
			)
			(layer "B.SilkS")
		)
		(fp_line
			(start -1.524 -0.762)
			(end -1.524 0.762)
			(stroke
				(width 0.1524)
				(type default)
			)
			(layer "B.SilkS")
		)
		(fp_line
			(start 1.524 -0.762)
			(end -1.524 -0.762)
			(stroke
				(width 0.1524)
				(type default)
			)
			(layer "B.SilkS")
		)
		(fp_line
			(start -1.1049 0.724916)
			(end -1.1049 -0.724916)
			(stroke
				(width 0.1)
				(type default)
			)
			(layer "B.Fab")
		)
		(fp_line
			(start 1.1049 0.724916)
			(end -1.1049 0.724916)
			(stroke
				(width 0.1)
				(type default)
			)
			(layer "B.Fab")
		)
		(fp_line
			(start -1.1049 -0.724916)
			(end 1.1049 -0.724916)
			(stroke
				(width 0.1)
				(type default)
			)
			(layer "B.Fab")
		)
		(fp_line
			(start 1.1049 -0.724916)
			(end 1.1049 0.724916)
			(stroke
				(width 0.1)
				(type default)
			)
			(layer "B.Fab")
		)
		(pad "1" smd rect
			(at 0.889 0 270)
			(size 1.016 1.27)
			(layers "B.Cu" "B.Mask" "B.Paste")
			(net "SW_P12V_AUX_PVDD11_S3_P0_FLT")
		)
		(pad "2" smd rect
			(at -0.889 0 270)
			(size 1.016 1.27)
			(layers "B.Cu" "B.Mask" "B.Paste")
			(net "GND")
		)
	)
	(footprint ""
		(layer "B.Cu")
		(at 225.9203 -402.744432 -90)
		(property "Reference" "PR3981"
			(at 0 0 90)
			(layer "B.SilkS")
			(hide yes)
			(effects
				(font
					(size 1.27 1.27)
				)
				(justify mirror)
			)
		)
		(property "Value" ""
			(at 0 0 90)
			(layer "B.Fab")
			(effects
				(font
					(size 1.27 1.27)
				)
				(justify mirror)
			)
		)
		(duplicate_pad_numbers_are_jumpers no)
		(fp_line
			(start -0.7874 0.4064)
			(end 0.7874 0.4064)
			(stroke
				(width 0.1524)
				(type default)
			)
			(layer "B.SilkS")
		)
		(fp_line
			(start 0.7874 0.4064)
			(end 0.7874 -0.4064)
			(stroke
				(width 0.1524)
				(type default)
			)
			(layer "B.SilkS")
		)
		(fp_line
			(start -0.7874 -0.4064)
			(end -0.7874 0.4064)
			(stroke
				(width 0.1524)
				(type default)
			)
			(layer "B.SilkS")
		)
		(fp_line
			(start 0.7874 -0.4064)
			(end -0.7874 -0.4064)
			(stroke
				(width 0.1524)
				(type default)
			)
			(layer "B.SilkS")
		)
		(fp_line
			(start -0.67945 0.3048)
			(end -0.120396 0.3048)
			(stroke
				(width 0.1)
				(type default)
			)
			(layer "B.Fab")
		)
		(fp_line
			(start -0.120396 0.3048)
			(end -0.120396 0.2794)
			(stroke
				(width 0.1)
				(type default)
			)
			(layer "B.Fab")
		)
		(fp_line
			(start 0.12065 0.3048)
			(end 0.67945 0.3048)
			(stroke
				(width 0.1)
				(type default)
			)
			(layer "B.Fab")
		)
		(fp_line
			(start 0.67945 0.3048)
			(end 0.67945 -0.305054)
			(stroke
				(width 0.1)
				(type default)
			)
			(layer "B.Fab")
		)
		(fp_line
			(start -0.120396 0.2794)
			(end 0.12065 0.2794)
			(stroke
				(width 0.1)
				(type default)
			)
			(layer "B.Fab")
		)
		(fp_line
			(start 0.12065 0.2794)
			(end 0.12065 0.3048)
			(stroke
				(width 0.1)
				(type default)
			)
			(layer "B.Fab")
		)
		(fp_line
			(start -0.12065 -0.2794)
			(end -0.12065 -0.3048)
			(stroke
				(width 0.1)
				(type default)
			)
			(layer "B.Fab")
		)
		(fp_line
			(start 0.12065 -0.2794)
			(end -0.12065 -0.2794)
			(stroke
				(width 0.1)
				(type default)
			)
			(layer "B.Fab")
		)
		(fp_line
			(start -0.67945 -0.3048)
			(end -0.67945 0.3048)
			(stroke
				(width 0.1)
				(type default)
			)
			(layer "B.Fab")
		)
		(fp_line
			(start -0.12065 -0.3048)
			(end -0.67945 -0.3048)
			(stroke
				(width 0.1)
				(type default)
			)
			(layer "B.Fab")
		)
		(fp_line
			(start 0.12065 -0.305054)
			(end 0.12065 -0.2794)
			(stroke
				(width 0.1)
				(type default)
			)
			(layer "B.Fab")
		)
		(fp_line
			(start 0.67945 -0.305054)
			(end 0.12065 -0.305054)
			(stroke
				(width 0.1)
				(type default)
			)
			(layer "B.Fab")
		)
		(pad "1" smd circle
			(at 0.40005 0 90)
			(size 0 0)
			(layers "B.Cu" "B.Mask" "B.Paste")
			(net "HSC_VDD_R_4")
		)
		(pad "2" smd circle
			(at -0.40005 0 90)
			(size 0 0)
			(layers "B.Cu" "B.Mask" "B.Paste")
			(net "HSC_VDD")
		)
	)
	(footprint ""
		(layer "B.Cu")
		(at 59.646058 -177.310542 90)
		(property "Reference" "PR337"
			(at 0 0 90)
			(layer "B.SilkS")
			(hide yes)
			(effects
				(font
					(size 1.27 1.27)
				)
				(justify mirror)
			)
		)
		(property "Value" ""
			(at 0 0 90)
			(layer "B.Fab")
			(effects
				(font
					(size 1.27 1.27)
				)
				(justify mirror)
			)
		)
		(duplicate_pad_numbers_are_jumpers no)
		(fp_line
			(start 0.7874 -0.4064)
			(end -0.7874 -0.4064)
			(stroke
				(width 0.1524)
				(type default)
			)
			(layer "B.SilkS")
		)
		(fp_line
			(start -0.7874 -0.4064)
			(end -0.7874 0.4064)
			(stroke
				(width 0.1524)
				(type default)
			)
			(layer "B.SilkS")
		)
		(fp_line
			(start 0.7874 0.4064)
			(end 0.7874 -0.4064)
			(stroke
				(width 0.1524)
				(type default)
			)
			(layer "B.SilkS")
		)
		(fp_line
			(start -0.7874 0.4064)
			(end 0.7874 0.4064)
			(stroke
				(width 0.1524)
				(type default)
			)
			(layer "B.SilkS")
		)
		(fp_line
			(start 0.67945 -0.305054)
			(end 0.12065 -0.305054)
			(stroke
				(width 0.1)
				(type default)
			)
			(layer "B.Fab")
		)
		(fp_line
			(start 0.12065 -0.305054)
			(end 0.12065 -0.2794)
			(stroke
				(width 0.1)
				(type default)
			)
			(layer "B.Fab")
		)
		(fp_line
			(start -0.12065 -0.3048)
			(end -0.67945 -0.3048)
			(stroke
				(width 0.1)
				(type default)
			)
			(layer "B.Fab")
		)
		(fp_line
			(start -0.67945 -0.3048)
			(end -0.67945 0.3048)
			(stroke
				(width 0.1)
				(type default)
			)
			(layer "B.Fab")
		)
		(fp_line
			(start 0.12065 -0.2794)
			(end -0.12065 -0.2794)
			(stroke
				(width 0.1)
				(type default)
			)
			(layer "B.Fab")
		)
		(fp_line
			(start -0.12065 -0.2794)
			(end -0.12065 -0.3048)
			(stroke
				(width 0.1)
				(type default)
			)
			(layer "B.Fab")
		)
		(fp_line
			(start 0.12065 0.2794)
			(end 0.12065 0.3048)
			(stroke
				(width 0.1)
				(type default)
			)
			(layer "B.Fab")
		)
		(fp_line
			(start -0.120396 0.2794)
			(end 0.12065 0.2794)
			(stroke
				(width 0.1)
				(type default)
			)
			(layer "B.Fab")
		)
		(fp_line
			(start 0.67945 0.3048)
			(end 0.67945 -0.305054)
			(stroke
				(width 0.1)
				(type default)
			)
			(layer "B.Fab")
		)
		(fp_line
			(start 0.12065 0.3048)
			(end 0.67945 0.3048)
			(stroke
				(width 0.1)
				(type default)
			)
			(layer "B.Fab")
		)
		(fp_line
			(start -0.120396 0.3048)
			(end -0.120396 0.2794)
			(stroke
				(width 0.1)
				(type default)
			)
			(layer "B.Fab")
		)
		(fp_line
			(start -0.67945 0.3048)
			(end -0.120396 0.3048)
			(stroke
				(width 0.1)
				(type default)
			)
			(layer "B.Fab")
		)
		(pad "1" smd circle
			(at 0.40005 0 270)
			(size 0 0)
			(layers "B.Cu" "B.Mask" "B.Paste")
			(net "PVDDCR_CPU0_P1")
		)
		(pad "2" smd circle
			(at -0.40005 0 270)
			(size 0 0)
			(layers "B.Cu" "B.Mask" "B.Paste")
			(net "GND")
		)
	)
)
